# T6G (Grand Teton) — schematic netlist excerpt (pin names and nets, part order shuffled) for the footprints in the layout excerpt that follows; sources: Cadence DE-HDL packaged netlist, KiCad conversion of 04192023_DAF0TMB3IC0_F0TG_MB_C_brd_V02_OCP.brd

PR390  Q_RES  0 5% EMPTY  pkg 0402LF  page 224 : A = PVDD11_S3_P1_RESET_N_R ; B = GND
PC2186  Q_CAP  1UF 25V 10% X6S  pkg C0402  page 262 : A = HSC_VDD_R ; B = AGND_HSC

(kicad_pcb
	(version 20260206)
	(generator "pcbnew")
	(generator_version "10.0")
	(general
		(thickness 1.6)
		(legacy_teardrops no)
	)
	(paper "A4")
	(title_block
		(title "04192023_DAF0TMB3IC0_F0TG_MB_C_brd_V02_OCP.brd")
		(comment 1 "Grand Teton / footprints 7606-7607 of 8354")
	)
	(layers
		(0 "F.Cu" signal "TOP")
		(4 "In1.Cu" signal "GND")
		(6 "In2.Cu" signal "IN1")
		(8 "In3.Cu" signal "GND1")
		(10 "In4.Cu" signal "IN2")
		(12 "In5.Cu" signal "GND2")
		(14 "In6.Cu" signal "IN3")
		(16 "In7.Cu" signal "GND3")
		(18 "In8.Cu" signal "VCC")
		(20 "In9.Cu" signal "VCC1")
		(22 "In10.Cu" signal "GND4")
		(24 "In11.Cu" signal "IN4")
		(26 "In12.Cu" signal "GND5")
		(28 "In13.Cu" signal "IN5")
		(30 "In14.Cu" signal "GND6")
		(32 "In15.Cu" signal "IN6")
		(34 "In16.Cu" signal "GND7")
		(2 "B.Cu" signal "BOTTOM")
		(9 "F.Adhes" user "F.Adhesive")
		(11 "B.Adhes" user "B.Adhesive")
		(13 "F.Paste" user "Package Geometry/Pastemask Top")
		(15 "B.Paste" user "Package Geometry/Pastemask Bottom")
		(5 "F.SilkS" user "Ref Des/Silkscreen Top")
		(7 "B.SilkS" user "Ref Des/Silkscreen Bottom")
		(1 "F.Mask" user "Board Geometry/Soldermask Top")
		(3 "B.Mask" user "Board Geometry/Soldermask Bottom")
		(17 "Dwgs.User" user "User.Drawings")
		(19 "Cmts.User" user "User.Comments")
		(21 "Eco1.User" user "User.Eco1")
		(23 "Eco2.User" user "User.Eco2")
		(25 "Edge.Cuts" user "Board Geometry/Outline")
		(27 "Margin" user)
		(31 "F.CrtYd" user "Package Geometry/Place Bound Top")
		(29 "B.CrtYd" user "Package Geometry/Place Bound Bottom")
		(35 "F.Fab" user "Ref Des/Assembly Top")
		(33 "B.Fab" user "Ref Des/Assembly Bottom")
	)
	(footprint ""
		(layer "B.Cu")
		(at 159.926782 -347.663008 180)
		(property "Reference" "PR390"
			(at 0 0 0)
			(layer "B.SilkS")
			(hide yes)
			(effects
				(font
					(size 1.27 1.27)
				)
				(justify mirror)
			)
		)
		(property "Value" ""
			(at 0 0 0)
			(layer "B.Fab")
			(effects
				(font
					(size 1.27 1.27)
				)
				(justify mirror)
			)
		)
		(duplicate_pad_numbers_are_jumpers no)
		(fp_line
			(start 0.7874 0.4064)
			(end 0.7874 -0.4064)
			(stroke
				(width 0.1524)
				(type default)
			)
			(layer "B.SilkS")
		)
		(fp_line
			(start 0.7874 -0.4064)
			(end -0.7874 -0.4064)
			(stroke
				(width 0.1524)
				(type default)
			)
			(layer "B.SilkS")
		)
		(fp_line
			(start -0.7874 0.4064)
			(end 0.7874 0.4064)
			(stroke
				(width 0.1524)
				(type default)
			)
			(layer "B.SilkS")
		)
		(fp_line
			(start -0.7874 -0.4064)
			(end -0.7874 0.4064)
			(stroke
				(width 0.1524)
				(type default)
			)
			(layer "B.SilkS")
		)
		(fp_line
			(start 0.67945 0.3048)
			(end 0.67945 -0.305054)
			(stroke
				(width 0.1)
				(type default)
			)
			(layer "B.Fab")
		)
		(fp_line
			(start 0.67945 -0.305054)
			(end 0.12065 -0.305054)
			(stroke
				(width 0.1)
				(type default)
			)
			(layer "B.Fab")
		)
		(fp_line
			(start 0.12065 0.3048)
			(end 0.67945 0.3048)
			(stroke
				(width 0.1)
				(type default)
			)
			(layer "B.Fab")
		)
		(fp_line
			(start 0.12065 0.2794)
			(end 0.12065 0.3048)
			(stroke
				(width 0.1)
				(type default)
			)
			(layer "B.Fab")
		)
		(fp_line
			(start 0.12065 -0.2794)
			(end -0.12065 -0.2794)
			(stroke
				(width 0.1)
				(type default)
			)
			(layer "B.Fab")
		)
		(fp_line
			(start 0.12065 -0.305054)
			(end 0.12065 -0.2794)
			(stroke
				(width 0.1)
				(type default)
			)
			(layer "B.Fab")
		)
		(fp_line
			(start -0.120396 0.3048)
			(end -0.120396 0.2794)
			(stroke
				(width 0.1)
				(type default)
			)
			(layer "B.Fab")
		)
		(fp_line
			(start -0.120396 0.2794)
			(end 0.12065 0.2794)
			(stroke
				(width 0.1)
				(type default)
			)
			(layer "B.Fab")
		)
		(fp_line
			(start -0.12065 -0.2794)
			(end -0.12065 -0.3048)
			(stroke
				(width 0.1)
				(type default)
			)
			(layer "B.Fab")
		)
		(fp_line
			(start -0.12065 -0.3048)
			(end -0.67945 -0.3048)
			(stroke
				(width 0.1)
				(type default)
			)
			(layer "B.Fab")
		)
		(fp_line
			(start -0.67945 0.3048)
			(end -0.120396 0.3048)
			(stroke
				(width 0.1)
				(type default)
			)
			(layer "B.Fab")
		)
		(fp_line
			(start -0.67945 -0.3048)
			(end -0.67945 0.3048)
			(stroke
				(width 0.1)
				(type default)
			)
			(layer "B.Fab")
		)
		(pad "1" smd circle
			(at 0.40005 0)
			(size 0 0)
			(layers "B.Cu" "B.Mask" "B.Paste")
			(net "PVDD11_S3_P1_RESET_N_R")
		)
		(pad "2" smd circle
			(at -0.40005 0)
			(size 0 0)
			(layers "B.Cu" "B.Mask" "B.Paste")
			(net "GND")
		)
	)
	(footprint ""
		(layer "B.Cu")
		(at 183.3753 -401.918932 -90)
		(property "Reference" "PC2186"
			(at 0 0 90)
			(layer "B.SilkS")
			(hide yes)
			(effects
				(font
					(size 1.27 1.27)
				)
				(justify mirror)
			)
		)
		(property "Value" ""
			(at 0 0 90)
			(layer "B.Fab")
			(effects
				(font
					(size 1.27 1.27)
				)
				(justify mirror)
			)
		)
		(duplicate_pad_numbers_are_jumpers no)
		(fp_line
			(start -0.7874 0.4064)
			(end 0.7874 0.4064)
			(stroke
				(width 0.1524)
				(type default)
			)
			(layer "B.SilkS")
		)
		(fp_line
			(start 0.7874 0.4064)
			(end 0.7874 -0.4064)
			(stroke
				(width 0.1524)
				(type default)
			)
			(layer "B.SilkS")
		)
		(fp_line
			(start -0.7874 -0.4064)
			(end -0.7874 0.4064)
			(stroke
				(width 0.1524)
				(type default)
			)
			(layer "B.SilkS")
		)
		(fp_line
			(start 0.7874 -0.4064)
			(end -0.7874 -0.4064)
			(stroke
				(width 0.1524)
				(type default)
			)
			(layer "B.SilkS")
		)
		(fp_line
			(start -0.67945 0.3048)
			(end -0.120396 0.3048)
			(stroke
				(width 0.1)
				(type default)
			)
			(layer "B.Fab")
		)
		(fp_line
			(start -0.120396 0.3048)
			(end -0.120396 0.2794)
			(stroke
				(width 0.1)
				(type default)
			)
			(layer "B.Fab")
		)
		(fp_line
			(start 0.12065 0.3048)
			(end 0.67945 0.3048)
			(stroke
				(width 0.1)
				(type default)
			)
			(layer "B.Fab")
		)
		(fp_line
			(start 0.67945 0.3048)
			(end 0.67945 -0.305054)
			(stroke
				(width 0.1)
				(type default)
			)
			(layer "B.Fab")
		)
		(fp_line
			(start -0.120396 0.2794)
			(end 0.12065 0.2794)
			(stroke
				(width 0.1)
				(type default)
			)
			(layer "B.Fab")
		)
		(fp_line
			(start 0.12065 0.2794)
			(end 0.12065 0.3048)
			(stroke
				(width 0.1)
				(type default)
			)
			(layer "B.Fab")
		)
		(fp_line
			(start -0.12065 -0.2794)
			(end -0.12065 -0.3048)
			(stroke
				(width 0.1)
				(type default)
			)
			(layer "B.Fab")
		)
		(fp_line
			(start 0.12065 -0.2794)
			(end -0.12065 -0.2794)
			(stroke
				(width 0.1)
				(type default)
			)
			(layer "B.Fab")
		)
		(fp_line
			(start -0.67945 -0.3048)
			(end -0.67945 0.3048)
			(stroke
				(width 0.1)
				(type default)
			)
			(layer "B.Fab")
		)
		(fp_line
			(start -0.12065 -0.3048)
			(end -0.67945 -0.3048)
			(stroke
				(width 0.1)
				(type default)
			)
			(layer "B.Fab")
		)
		(fp_line
			(start 0.12065 -0.305054)
			(end 0.12065 -0.2794)
			(stroke
				(width 0.1)
				(type default)
			)
			(layer "B.Fab")
		)
		(fp_line
			(start 0.67945 -0.305054)
			(end 0.12065 -0.305054)
			(stroke
				(width 0.1)
				(type default)
			)
			(layer "B.Fab")
		)
		(pad "1" smd circle
			(at 0.40005 0 90)
			(size 0 0)
			(layers "B.Cu" "B.Mask" "B.Paste")
			(net "HSC_VDD_R")
		)
		(pad "2" smd circle
			(at -0.40005 0 90)
			(size 0 0)
			(layers "B.Cu" "B.Mask" "B.Paste")
			(net "AGND_HSC")
		)
	)
)
